(kicad_pcb
	(version 20260206)
	(generator "pcbnew")
	(generator_version "10.0")
	(general
		(thickness 1.6)
		(legacy_teardrops no)
	)
	(paper "A4")
	(title_block
		(title "01162023_DA0F0TEBIF0_F0T_Expander_BD_F_brd_V02_OCP.brd")
		(comment 1 "Grand Teton / footprints 8820-8827 of 9728")
	)
	(layers
		(0 "F.Cu" signal "TOP")
		(4 "In1.Cu" signal "GND")
		(6 "In2.Cu" signal "VCC")
		(8 "In3.Cu" signal "VCC1")
		(10 "In4.Cu" signal "GND1")
		(12 "In5.Cu" signal "IN1")
		(14 "In6.Cu" signal "GND2")
		(16 "In7.Cu" signal "IN2")
		(18 "In8.Cu" signal "GND3")
		(20 "In9.Cu" signal "IN3")
		(22 "In10.Cu" signal "GND4")
		(24 "In11.Cu" signal "IN4")
		(26 "In12.Cu" signal "GND5")
		(28 "In13.Cu" signal "IN5")
		(30 "In14.Cu" signal "GND6")
		(32 "In15.Cu" signal "IN6")
		(34 "In16.Cu" signal "GND7")
		(2 "B.Cu" signal "BOTTOM")
		(9 "F.Adhes" user "F.Adhesive")
		(11 "B.Adhes" user "B.Adhesive")
		(13 "F.Paste" user "Package Geometry/Pastemask Top")
		(15 "B.Paste" user "Package Geometry/Pastemask Bottom")
		(5 "F.SilkS" user "Ref Des/Silkscreen Top")
		(7 "B.SilkS" user "Ref Des/Silkscreen Bottom")
		(1 "F.Mask" user "Board Geometry/Soldermask Top")
		(3 "B.Mask" user "Board Geometry/Soldermask Bottom")
		(17 "Dwgs.User" user "User.Drawings")
		(19 "Cmts.User" user "User.Comments")
		(21 "Eco1.User" user "User.Eco1")
		(23 "Eco2.User" user "User.Eco2")
		(25 "Edge.Cuts" user "Board Geometry/Outline")
		(27 "Margin" user)
		(31 "F.CrtYd" user "Package Geometry/Place Bound Top")
		(29 "B.CrtYd" user "Package Geometry/Place Bound Bottom")
		(35 "F.Fab" user "Ref Des/Assembly Top")
		(33 "B.Fab" user "Ref Des/Assembly Bottom")
	)
	(footprint ""
		(layer "B.Cu")
		(at 100.12045 -356.333806 -90)
		(property "Reference" "C4176"
			(at 0 0 90)
			(layer "B.SilkS")
			(hide yes)
			(effects
				(font
					(size 1.27 1.27)
				)
				(justify mirror)
			)
		)
		(property "Value" ""
			(at 0 0 90)
			(layer "B.Fab")
			(effects
				(font
					(size 1.27 1.27)
				)
				(justify mirror)
			)
		)
		(duplicate_pad_numbers_are_jumpers no)
		(fp_line
			(start -1.524 0.762)
			(end 1.524 0.762)
			(stroke
				(width 0.1524)
				(type default)
			)
			(layer "B.SilkS")
		)
		(fp_line
			(start 1.524 0.762)
			(end 1.524 -0.762)
			(stroke
				(width 0.1524)
				(type default)
			)
			(layer "B.SilkS")
		)
		(fp_line
			(start -1.524 -0.762)
			(end -1.524 0.762)
			(stroke
				(width 0.1524)
				(type default)
			)
			(layer "B.SilkS")
		)
		(fp_line
			(start 1.524 -0.762)
			(end -1.524 -0.762)
			(stroke
				(width 0.1524)
				(type default)
			)
			(layer "B.SilkS")
		)
		(fp_line
			(start -1.1049 0.724916)
			(end -1.1049 -0.724916)
			(stroke
				(width 0.1)
				(type default)
			)
			(layer "B.Fab")
		)
		(fp_line
			(start 1.1049 0.724916)
			(end -1.1049 0.724916)
			(stroke
				(width 0.1)
				(type default)
			)
			(layer "B.Fab")
		)
		(fp_line
			(start -1.1049 -0.724916)
			(end 1.1049 -0.724916)
			(stroke
				(width 0.1)
				(type default)
			)
			(layer "B.Fab")
		)
		(fp_line
			(start 1.1049 -0.724916)
			(end 1.1049 0.724916)
			(stroke
				(width 0.1)
				(type default)
			)
			(layer "B.Fab")
		)
		(pad "1" smd rect
			(at 0.889 0 270)
			(size 1.016 1.27)
			(layers "B.Cu" "B.Mask" "B.Paste")
			(net "P3V3_CLK_BUFFER_9ZXL0451E_S3_VZX3P3")
		)
		(pad "2" smd rect
			(at -0.889 0 270)
			(size 1.016 1.27)
			(layers "B.Cu" "B.Mask" "B.Paste")
			(net "GND")
		)
	)
	(footprint ""
		(layer "B.Cu")
		(at 148.209254 -203.466192 -90)
		(property "Reference" "U104"
			(at 0.08763 1.838706 270)
			(unlocked yes)
			(layer "B.SilkS")
			(effects
				(font
					(size 0.7874 0.5842)
					(thickness 0.1524)
				)
				(justify mirror)
			)
		)
		(property "Value" ""
			(at 0 0 90)
			(layer "B.Fab")
			(effects
				(font
					(size 1.27 1.27)
				)
				(justify mirror)
			)
		)
		(duplicate_pad_numbers_are_jumpers no)
		(fp_line
			(start -1.7272 1.1176)
			(end 1.7272 1.1176)
			(stroke
				(width 0.1524)
				(type default)
			)
			(layer "B.SilkS")
		)
		(fp_line
			(start 1.7272 1.1176)
			(end 1.7272 -1.1176)
			(stroke
				(width 0.1524)
				(type default)
			)
			(layer "B.SilkS")
		)
		(fp_line
			(start 0 -0.7366)
			(end 0.254 -1.1176)
			(stroke
				(width 0.1524)
				(type default)
			)
			(layer "B.SilkS")
		)
		(fp_line
			(start -1.7272 -1.1176)
			(end -1.7272 1.1176)
			(stroke
				(width 0.1524)
				(type default)
			)
			(layer "B.SilkS")
		)
		(fp_line
			(start -1.7272 -1.1176)
			(end -0.254 -1.1176)
			(stroke
				(width 0.1524)
				(type default)
			)
			(layer "B.SilkS")
		)
		(fp_line
			(start -0.254 -1.1176)
			(end 0 -0.7366)
			(stroke
				(width 0.1524)
				(type default)
			)
			(layer "B.SilkS")
		)
		(fp_line
			(start 0.254 -1.1176)
			(end 1.7272 -1.1176)
			(stroke
				(width 0.1524)
				(type default)
			)
			(layer "B.SilkS")
		)
		(fp_poly
			(pts
				(xy 1.9558 -0.649986) (xy 2.7178 -0.268986) (xy 2.7178 -1.030986)
			)
			(stroke
				(width 0)
				(type default)
			)
			(fill yes)
			(layer "B.SilkS")
		)
		(fp_line
			(start -1.5748 1.1176)
			(end -1.5748 -1.1176)
			(stroke
				(width 0.1)
				(type default)
			)
			(layer "B.Fab")
		)
		(fp_line
			(start 1.5748 1.1176)
			(end -1.5748 1.1176)
			(stroke
				(width 0.1)
				(type default)
			)
			(layer "B.Fab")
		)
		(fp_line
			(start -1.5748 -1.1176)
			(end 1.5748 -1.1176)
			(stroke
				(width 0.1)
				(type default)
			)
			(layer "B.Fab")
		)
		(fp_line
			(start 1.5748 -1.1176)
			(end 1.5748 1.1176)
			(stroke
				(width 0.1)
				(type default)
			)
			(layer "B.Fab")
		)
		(fp_poly
			(pts
				(xy 1.9558 -0.649986) (xy 2.7178 -0.268986) (xy 2.7178 -1.030986)
			)
			(stroke
				(width 0)
				(type default)
			)
			(fill yes)
			(layer "B.Fab")
		)
		(pad "1" smd rect
			(at 0.999998 -0.649986 180)
			(size 0.3556 1.1176)
			(layers "B.Cu" "B.Mask" "B.Paste")
			(net "UART_PEX0_CLI_R_RX")
		)
		(pad "2" smd rect
			(at 0.999998 0 180)
			(size 0.3556 1.1176)
			(layers "B.Cu" "B.Mask" "B.Paste")
			(net "GND")
		)
		(pad "3" smd rect
			(at 0.999998 0.649986 180)
			(size 0.3556 1.1176)
			(layers "B.Cu" "B.Mask" "B.Paste")
			(net "UART_PEX1_CLI_R_RX")
		)
		(pad "4" smd rect
			(at -0.999998 0.649986 180)
			(size 0.3556 1.1176)
			(layers "B.Cu" "B.Mask" "B.Paste")
			(net "UART_PEX1_CLI_BUF_R_RX")
		)
		(pad "5" smd rect
			(at -0.999998 0 180)
			(size 0.3556 1.1176)
			(layers "B.Cu" "B.Mask" "B.Paste")
			(net "P3V3_AUX")
		)
		(pad "6" smd rect
			(at -0.999998 -0.649986 180)
			(size 0.3556 1.1176)
			(layers "B.Cu" "B.Mask" "B.Paste")
			(net "UART_PEX0_CLI_BUF_R_RX")
		)
	)
	(footprint ""
		(layer "B.Cu")
		(at 332.940914 -323.76745 -90)
		(property "Reference" "C4308"
			(at 0 0 90)
			(layer "B.SilkS")
			(hide yes)
			(effects
				(font
					(size 1.27 1.27)
				)
				(justify mirror)
			)
		)
		(property "Value" ""
			(at 0 0 90)
			(layer "B.Fab")
			(effects
				(font
					(size 1.27 1.27)
				)
				(justify mirror)
			)
		)
		(duplicate_pad_numbers_are_jumpers no)
		(fp_line
			(start -0.299974 0.150114)
			(end 0.299974 0.150114)
			(stroke
				(width 0.1)
				(type default)
			)
			(layer "B.Fab")
		)
		(fp_line
			(start 0.299974 0.150114)
			(end 0.299974 -0.150114)
			(stroke
				(width 0.1)
				(type default)
			)
			(layer "B.Fab")
		)
		(fp_line
			(start -0.299974 -0.150114)
			(end -0.299974 0.150114)
			(stroke
				(width 0.1)
				(type default)
			)
			(layer "B.Fab")
		)
		(fp_line
			(start 0.299974 -0.150114)
			(end -0.299974 -0.150114)
			(stroke
				(width 0.1)
				(type default)
			)
			(layer "B.Fab")
		)
		(pad "1" smd rect
			(at 0.2667 0 90)
			(size 0.3048 0.381)
			(layers "B.Cu" "B.Mask" "B.Paste")
			(net "P0V8_SERDES_VDDA_PEX2")
		)
		(pad "2" smd rect
			(at -0.2667 0 90)
			(size 0.3048 0.381)
			(layers "B.Cu" "B.Mask" "B.Paste")
			(net "GND")
		)
	)
	(footprint ""
		(layer "B.Cu")
		(at 265.53668 -85.713316 180)
		(property "Reference" "C2649"
			(at 0 0 0)
			(layer "B.SilkS")
			(hide yes)
			(effects
				(font
					(size 1.27 1.27)
				)
				(justify mirror)
			)
		)
		(property "Value" ""
			(at 0 0 0)
			(layer "B.Fab")
			(effects
				(font
					(size 1.27 1.27)
				)
				(justify mirror)
			)
		)
		(duplicate_pad_numbers_are_jumpers no)
		(fp_line
			(start 0.7874 0.4064)
			(end 0.7874 -0.4064)
			(stroke
				(width 0.1524)
				(type default)
			)
			(layer "B.SilkS")
		)
		(fp_line
			(start 0.7874 -0.4064)
			(end -0.7874 -0.4064)
			(stroke
				(width 0.1524)
				(type default)
			)
			(layer "B.SilkS")
		)
		(fp_line
			(start -0.7874 0.4064)
			(end 0.7874 0.4064)
			(stroke
				(width 0.1524)
				(type default)
			)
			(layer "B.SilkS")
		)
		(fp_line
			(start -0.7874 -0.4064)
			(end -0.7874 0.4064)
			(stroke
				(width 0.1524)
				(type default)
			)
			(layer "B.SilkS")
		)
		(fp_line
			(start 0.67945 0.3048)
			(end 0.67945 -0.305054)
			(stroke
				(width 0.1)
				(type default)
			)
			(layer "B.Fab")
		)
		(fp_line
			(start 0.67945 -0.305054)
			(end 0.12065 -0.305054)
			(stroke
				(width 0.1)
				(type default)
			)
			(layer "B.Fab")
		)
		(fp_line
			(start 0.12065 0.3048)
			(end 0.67945 0.3048)
			(stroke
				(width 0.1)
				(type default)
			)
			(layer "B.Fab")
		)
		(fp_line
			(start 0.12065 0.2794)
			(end 0.12065 0.3048)
			(stroke
				(width 0.1)
				(type default)
			)
			(layer "B.Fab")
		)
		(fp_line
			(start 0.12065 -0.2794)
			(end -0.12065 -0.2794)
			(stroke
				(width 0.1)
				(type default)
			)
			(layer "B.Fab")
		)
		(fp_line
			(start 0.12065 -0.305054)
			(end 0.12065 -0.2794)
			(stroke
				(width 0.1)
				(type default)
			)
			(layer "B.Fab")
		)
		(fp_line
			(start -0.120396 0.3048)
			(end -0.120396 0.2794)
			(stroke
				(width 0.1)
				(type default)
			)
			(layer "B.Fab")
		)
		(fp_line
			(start -0.120396 0.2794)
			(end 0.12065 0.2794)
			(stroke
				(width 0.1)
				(type default)
			)
			(layer "B.Fab")
		)
		(fp_line
			(start -0.12065 -0.2794)
			(end -0.12065 -0.3048)
			(stroke
				(width 0.1)
				(type default)
			)
			(layer "B.Fab")
		)
		(fp_line
			(start -0.12065 -0.3048)
			(end -0.67945 -0.3048)
			(stroke
				(width 0.1)
				(type default)
			)
			(layer "B.Fab")
		)
		(fp_line
			(start -0.67945 0.3048)
			(end -0.120396 0.3048)
			(stroke
				(width 0.1)
				(type default)
			)
			(layer "B.Fab")
		)
		(fp_line
			(start -0.67945 -0.3048)
			(end -0.67945 0.3048)
			(stroke
				(width 0.1)
				(type default)
			)
			(layer "B.Fab")
		)
		(pad "1" smd circle
			(at 0.40005 0)
			(size 0 0)
			(layers "B.Cu" "B.Mask" "B.Paste")
			(net "P3V3_CLK_GEN_VDDMXCK_CK440")
		)
		(pad "2" smd circle
			(at -0.40005 0)
			(size 0 0)
			(layers "B.Cu" "B.Mask" "B.Paste")
			(net "GND")
		)
	)
	(footprint ""
		(layer "B.Cu")
		(at 232.645712 -207.767428)
		(property "Reference" "R6151"
			(at 0 0 0)
			(layer "B.SilkS")
			(hide yes)
			(effects
				(font
					(size 1.27 1.27)
				)
				(justify mirror)
			)
		)
		(property "Value" ""
			(at 0 0 0)
			(layer "B.Fab")
			(effects
				(font
					(size 1.27 1.27)
				)
				(justify mirror)
			)
		)
		(duplicate_pad_numbers_are_jumpers no)
		(fp_line
			(start -0.7874 -0.4064)
			(end -0.7874 0.4064)
			(stroke
				(width 0.1524)
				(type default)
			)
			(layer "B.SilkS")
		)
		(fp_line
			(start -0.7874 0.4064)
			(end 0.7874 0.4064)
			(stroke
				(width 0.1524)
				(type default)
			)
			(layer "B.SilkS")
		)
		(fp_line
			(start 0.7874 -0.4064)
			(end -0.7874 -0.4064)
			(stroke
				(width 0.1524)
				(type default)
			)
			(layer "B.SilkS")
		)
		(fp_line
			(start 0.7874 0.4064)
			(end 0.7874 -0.4064)
			(stroke
				(width 0.1524)
				(type default)
			)
			(layer "B.SilkS")
		)
		(fp_line
			(start -0.67945 -0.3048)
			(end -0.67945 0.3048)
			(stroke
				(width 0.1)
				(type default)
			)
			(layer "B.Fab")
		)
		(fp_line
			(start -0.67945 0.3048)
			(end -0.120396 0.3048)
			(stroke
				(width 0.1)
				(type default)
			)
			(layer "B.Fab")
		)
		(fp_line
			(start -0.12065 -0.3048)
			(end -0.67945 -0.3048)
			(stroke
				(width 0.1)
				(type default)
			)
			(layer "B.Fab")
		)
		(fp_line
			(start -0.12065 -0.2794)
			(end -0.12065 -0.3048)
			(stroke
				(width 0.1)
				(type default)
			)
			(layer "B.Fab")
		)
		(fp_line
			(start -0.120396 0.2794)
			(end 0.12065 0.2794)
			(stroke
				(width 0.1)
				(type default)
			)
			(layer "B.Fab")
		)
		(fp_line
			(start -0.120396 0.3048)
			(end -0.120396 0.2794)
			(stroke
				(width 0.1)
				(type default)
			)
			(layer "B.Fab")
		)
		(fp_line
			(start 0.12065 -0.305054)
			(end 0.12065 -0.2794)
			(stroke
				(width 0.1)
				(type default)
			)
			(layer "B.Fab")
		)
		(fp_line
			(start 0.12065 -0.2794)
			(end -0.12065 -0.2794)
			(stroke
				(width 0.1)
				(type default)
			)
			(layer "B.Fab")
		)
		(fp_line
			(start 0.12065 0.2794)
			(end 0.12065 0.3048)
			(stroke
				(width 0.1)
				(type default)
			)
			(layer "B.Fab")
		)
		(fp_line
			(start 0.12065 0.3048)
			(end 0.67945 0.3048)
			(stroke
				(width 0.1)
				(type default)
			)
			(layer "B.Fab")
		)
		(fp_line
			(start 0.67945 -0.305054)
			(end 0.12065 -0.305054)
			(stroke
				(width 0.1)
				(type default)
			)
			(layer "B.Fab")
		)
		(fp_line
			(start 0.67945 0.3048)
			(end 0.67945 -0.305054)
			(stroke
				(width 0.1)
				(type default)
			)
			(layer "B.Fab")
		)
		(pad "1" smd circle
			(at 0.40005 0 180)
			(size 0 0)
			(layers "B.Cu" "B.Mask" "B.Paste")
			(net "BIC_SPI1DQ2")
		)
		(pad "2" smd circle
			(at -0.40005 0 180)
			(size 0 0)
			(layers "B.Cu" "B.Mask" "B.Paste")
			(net "P3V3_AUX")
		)
	)
	(footprint ""
		(layer "B.Cu")
		(at 409.374848 -286.399732 90)
		(property "Reference" "C3478"
			(at 0 0 90)
			(layer "B.SilkS")
			(hide yes)
			(effects
				(font
					(size 1.27 1.27)
				)
				(justify mirror)
			)
		)
		(property "Value" ""
			(at 0 0 90)
			(layer "B.Fab")
			(effects
				(font
					(size 1.27 1.27)
				)
				(justify mirror)
			)
		)
		(duplicate_pad_numbers_are_jumpers no)
		(fp_line
			(start 0.299974 -0.150114)
			(end -0.299974 -0.150114)
			(stroke
				(width 0.1)
				(type default)
			)
			(layer "B.Fab")
		)
		(fp_line
			(start -0.299974 -0.150114)
			(end -0.299974 0.150114)
			(stroke
				(width 0.1)
				(type default)
			)
			(layer "B.Fab")
		)
		(fp_line
			(start 0.299974 0.150114)
			(end 0.299974 -0.150114)
			(stroke
				(width 0.1)
				(type default)
			)
			(layer "B.Fab")
		)
		(fp_line
			(start -0.299974 0.150114)
			(end 0.299974 0.150114)
			(stroke
				(width 0.1)
				(type default)
			)
			(layer "B.Fab")
		)
		(pad "1" smd rect
			(at 0.2667 0 270)
			(size 0.3048 0.381)
			(layers "B.Cu" "B.Mask" "B.Paste")
			(net "P1V25_SERDES_VDDPLL_PEX3")
		)
		(pad "2" smd rect
			(at -0.2667 0 270)
			(size 0.3048 0.381)
			(layers "B.Cu" "B.Mask" "B.Paste")
			(net "GND")
		)
	)
	(footprint ""
		(layer "B.Cu")
		(at 345.44 -207.772 -90)
		(property "Reference" "R4146"
			(at 0 0 90)
			(layer "B.SilkS")
			(hide yes)
			(effects
				(font
					(size 1.27 1.27)
				)
				(justify mirror)
			)
		)
		(property "Value" ""
			(at 0 0 90)
			(layer "B.Fab")
			(effects
				(font
					(size 1.27 1.27)
				)
				(justify mirror)
			)
		)
		(duplicate_pad_numbers_are_jumpers no)
		(fp_line
			(start -0.7874 0.4064)
			(end 0.7874 0.4064)
			(stroke
				(width 0.1524)
				(type default)
			)
			(layer "B.SilkS")
		)
		(fp_line
			(start 0.7874 0.4064)
			(end 0.7874 -0.4064)
			(stroke
				(width 0.1524)
				(type default)
			)
			(layer "B.SilkS")
		)
		(fp_line
			(start -0.7874 -0.4064)
			(end -0.7874 0.4064)
			(stroke
				(width 0.1524)
				(type default)
			)
			(layer "B.SilkS")
		)
		(fp_line
			(start 0.7874 -0.4064)
			(end -0.7874 -0.4064)
			(stroke
				(width 0.1524)
				(type default)
			)
			(layer "B.SilkS")
		)
		(fp_line
			(start -0.67945 0.3048)
			(end -0.120396 0.3048)
			(stroke
				(width 0.1)
				(type default)
			)
			(layer "B.Fab")
		)
		(fp_line
			(start -0.120396 0.3048)
			(end -0.120396 0.2794)
			(stroke
				(width 0.1)
				(type default)
			)
			(layer "B.Fab")
		)
		(fp_line
			(start 0.12065 0.3048)
			(end 0.67945 0.3048)
			(stroke
				(width 0.1)
				(type default)
			)
			(layer "B.Fab")
		)
		(fp_line
			(start 0.67945 0.3048)
			(end 0.67945 -0.305054)
			(stroke
				(width 0.1)
				(type default)
			)
			(layer "B.Fab")
		)
		(fp_line
			(start -0.120396 0.2794)
			(end 0.12065 0.2794)
			(stroke
				(width 0.1)
				(type default)
			)
			(layer "B.Fab")
		)
		(fp_line
			(start 0.12065 0.2794)
			(end 0.12065 0.3048)
			(stroke
				(width 0.1)
				(type default)
			)
			(layer "B.Fab")
		)
		(fp_line
			(start -0.12065 -0.2794)
			(end -0.12065 -0.3048)
			(stroke
				(width 0.1)
				(type default)
			)
			(layer "B.Fab")
		)
		(fp_line
			(start 0.12065 -0.2794)
			(end -0.12065 -0.2794)
			(stroke
				(width 0.1)
				(type default)
			)
			(layer "B.Fab")
		)
		(fp_line
			(start -0.67945 -0.3048)
			(end -0.67945 0.3048)
			(stroke
				(width 0.1)
				(type default)
			)
			(layer "B.Fab")
		)
		(fp_line
			(start -0.12065 -0.3048)
			(end -0.67945 -0.3048)
			(stroke
				(width 0.1)
				(type default)
			)
			(layer "B.Fab")
		)
		(fp_line
			(start 0.12065 -0.305054)
			(end 0.12065 -0.2794)
			(stroke
				(width 0.1)
				(type default)
			)
			(layer "B.Fab")
		)
		(fp_line
			(start 0.67945 -0.305054)
			(end 0.12065 -0.305054)
			(stroke
				(width 0.1)
				(type default)
			)
			(layer "B.Fab")
		)
		(pad "1" smd circle
			(at 0.40005 0 90)
			(size 0 0)
			(layers "B.Cu" "B.Mask" "B.Paste")
			(net "SSD15_CLK_EN_R_N")
		)
		(pad "2" smd circle
			(at -0.40005 0 90)
			(size 0 0)
			(layers "B.Cu" "B.Mask" "B.Paste")
			(net "SSD15_CLK_EN_N")
		)
	)
	(footprint ""
		(layer "B.Cu")
		(at 170.049952 -290.199826 90)
		(property "Reference" "C1486"
			(at 0 0 90)
			(layer "B.SilkS")
			(hide yes)
			(effects
				(font
					(size 1.27 1.27)
				)
				(justify mirror)
			)
		)
		(property "Value" ""
			(at 0 0 90)
			(layer "B.Fab")
			(effects
				(font
					(size 1.27 1.27)
				)
				(justify mirror)
			)
		)
		(duplicate_pad_numbers_are_jumpers no)
		(fp_line
			(start 0.299974 -0.150114)
			(end -0.299974 -0.150114)
			(stroke
				(width 0.1)
				(type default)
			)
			(layer "B.Fab")
		)
		(fp_line
			(start -0.299974 -0.150114)
			(end -0.299974 0.150114)
			(stroke
				(width 0.1)
				(type default)
			)
			(layer "B.Fab")
		)
		(fp_line
			(start 0.299974 0.150114)
			(end 0.299974 -0.150114)
			(stroke
				(width 0.1)
				(type default)
			)
			(layer "B.Fab")
		)
		(fp_line
			(start -0.299974 0.150114)
			(end 0.299974 0.150114)
			(stroke
				(width 0.1)
				(type default)
			)
			(layer "B.Fab")
		)
		(pad "1" smd rect
			(at 0.2667 0 270)
			(size 0.3048 0.381)
			(layers "B.Cu" "B.Mask" "B.Paste")
			(net "P0V8_SERDES_VDDA_PEX1")
		)
		(pad "2" smd rect
			(at -0.2667 0 270)
			(size 0.3048 0.381)
			(layers "B.Cu" "B.Mask" "B.Paste")
			(net "GND")
		)
	)
)
